(kicad_pcb
	(version 20260206)
	(generator "pcbnew")
	(generator_version "10.0")
	(general
		(thickness 1.6)
		(legacy_teardrops no)
	)
	(paper "A4")
	(title_block
		(title "baseboard — 13948-1b.1110WZS1818.brd")
		(comment 1 "Honey Badger (Wiwynn) / footprints 1936-1945 of 2523")
	)
	(layers
		(0 "F.Cu" signal "TOP")
		(4 "In1.Cu" signal "L2GND")
		(6 "In2.Cu" signal "L3")
		(8 "In3.Cu" signal "L4VCC")
		(10 "In4.Cu" signal "L5VCC")
		(12 "In5.Cu" signal "L6")
		(14 "In6.Cu" signal "L7GND")
		(2 "B.Cu" signal "BOTTOM")
		(9 "F.Adhes" user "F.Adhesive")
		(11 "B.Adhes" user "B.Adhesive")
		(13 "F.Paste" user "Package Geometry/Pastemask Top")
		(15 "B.Paste" user "Package Geometry/Pastemask Bottom")
		(5 "F.SilkS" user "Ref Des/Silkscreen Top")
		(7 "B.SilkS" user "Ref Des/Silkscreen Bottom")
		(1 "F.Mask" user "Board Geometry/Soldermask Top")
		(3 "B.Mask" user "Board Geometry/Soldermask Bottom")
		(17 "Dwgs.User" user "User.Drawings")
		(19 "Cmts.User" user "User.Comments")
		(21 "Eco1.User" user "User.Eco1")
		(23 "Eco2.User" user "User.Eco2")
		(25 "Edge.Cuts" user "Board Geometry/Outline")
		(27 "Margin" user)
		(31 "F.CrtYd" user "Package Geometry/Place Bound Top")
		(29 "B.CrtYd" user "Package Geometry/Place Bound Bottom")
		(35 "F.Fab" user "Ref Des/Assembly Top")
		(33 "B.Fab" user "Ref Des/Assembly Bottom")
	)
	(footprint ""
		(layer "B.Cu")
		(at 303.8983 -177.42408 90)
		(property "Reference" "C219"
			(at 0 0 90)
			(layer "B.SilkS")
			(hide yes)
			(effects
				(font
					(size 1.27 1.27)
				)
				(justify mirror)
			)
		)
		(property "Value" "SC1U10V3KX-4GP-U"
			(at 0 -2.8194 90)
			(unlocked yes)
			(layer "B.Fab")
			(hide yes)
			(effects
				(font
					(size 1.016 1.016)
					(thickness 0.1524)
				)
				(justify mirror)
			)
		)
		(property "Device Type" "C603H36"
			(at 0 -4.3434 90)
			(unlocked yes)
			(layer "B.Fab")
			(hide yes)
			(effects
				(font
					(size 1.016 1.016)
					(thickness 0.1524)
				)
				(justify mirror)
			)
		)
		(duplicate_pad_numbers_are_jumpers no)
		(fp_line
			(start -0.508 0)
			(end 0.508 0)
			(stroke
				(width 0.2032)
				(type default)
			)
			(layer "B.SilkS")
		)
		(fp_rect
			(start 0.5842 1.3335)
			(end -0.5842 -1.3335)
			(stroke
				(width 0)
				(type default)
			)
			(fill no)
			(layer "B.CrtYd")
		)
		(fp_rect
			(start 0.5842 1.3335)
			(end -0.5842 -1.3335)
			(stroke
				(width 0)
				(type default)
			)
			(fill no)
			(layer "B.Fab")
		)
		(pad "1" smd custom
			(at 0 -0.762 270)
			(size 0.2159 0.2159)
			(layers "B.Cu" "B.Mask" "B.Paste")
			(net "P3V3_STBY")
			(options
				(clearance outline)
				(anchor circle)
			)
			(primitives
				(gr_poly
					(pts
						(arc
							(start -0.3302 0.4318)
							(mid -0.402042 0.402042)
							(end -0.4318 0.3302)
						)
						(arc
							(start -0.4318 -0.3302)
							(mid -0.402042 -0.402042)
							(end -0.3302 -0.4318)
						)
						(arc
							(start 0.3302 -0.4318)
							(mid 0.402042 -0.402042)
							(end 0.4318 -0.3302)
						)
						(arc
							(start 0.4318 0.3302)
							(mid 0.402042 0.402042)
							(end 0.3302 0.4318)
						)
					)
					(width 0)
					(fill yes)
				)
			)
		)
		(pad "2" smd custom
			(at 0 0.762 270)
			(size 0.2159 0.2159)
			(layers "B.Cu" "B.Mask" "B.Paste")
			(net "GND")
			(options
				(clearance outline)
				(anchor circle)
			)
			(primitives
				(gr_poly
					(pts
						(arc
							(start -0.3302 0.4318)
							(mid -0.402042 0.402042)
							(end -0.4318 0.3302)
						)
						(arc
							(start -0.4318 -0.3302)
							(mid -0.402042 -0.402042)
							(end -0.3302 -0.4318)
						)
						(arc
							(start 0.3302 -0.4318)
							(mid 0.402042 -0.402042)
							(end 0.4318 -0.3302)
						)
						(arc
							(start 0.4318 0.3302)
							(mid 0.402042 0.402042)
							(end 0.3302 0.4318)
						)
					)
					(width 0)
					(fill yes)
				)
			)
		)
	)
	(footprint ""
		(layer "B.Cu")
		(at 78.982062 -57.874408 -90)
		(property "Reference" "SC924"
			(at 0 0 90)
			(layer "B.SilkS")
			(hide yes)
			(effects
				(font
					(size 1.27 1.27)
				)
				(justify mirror)
			)
		)
		(property "Value" "SC10U6D3V5KX-4GP"
			(at 0.0762 -6.1214 270)
			(unlocked yes)
			(layer "B.Fab")
			(hide yes)
			(effects
				(font
					(size 1.016 1.016)
					(thickness 0.1524)
				)
				(justify mirror)
			)
		)
		(property "Device Type" "C805H58"
			(at 0.0762 -8.1534 270)
			(unlocked yes)
			(layer "B.Fab")
			(hide yes)
			(effects
				(font
					(size 1.016 1.016)
					(thickness 0.1524)
				)
				(justify mirror)
			)
		)
		(duplicate_pad_numbers_are_jumpers no)
		(fp_line
			(start -0.635 0)
			(end 0.635 0)
			(stroke
				(width 0.508)
				(type default)
			)
			(layer "B.SilkS")
		)
		(fp_rect
			(start 0.9652 1.778)
			(end -0.9652 -1.778)
			(stroke
				(width 0)
				(type default)
			)
			(fill no)
			(layer "B.CrtYd")
		)
		(fp_poly
			(pts
				(xy 0.9652 -1.778) (xy -0.9652 -1.778) (xy -0.9652 1.778) (xy 0.9652 1.778)
			)
			(stroke
				(width 0)
				(type default)
			)
			(fill no)
			(layer "B.Fab")
		)
		(pad "1" smd rect
			(at 0 -0.9652 90)
			(size 1.397 1.143)
			(layers "B.Cu" "B.Mask" "B.Paste")
			(net "VDDA_SAS_REF_CLK")
		)
		(pad "2" smd rect
			(at 0 0.9652 90)
			(size 1.397 1.143)
			(layers "B.Cu" "B.Mask" "B.Paste")
			(net "GND")
		)
	)
	(footprint ""
		(layer "B.Cu")
		(at 112.91316 -31.115)
		(property "Reference" "STP139"
			(at 0 0 0)
			(layer "B.SilkS")
			(hide yes)
			(effects
				(font
					(size 1.27 1.27)
				)
				(justify mirror)
			)
		)
		(property "Value" "TPAD28"
			(at -0.0127 -1.8034 0)
			(unlocked yes)
			(layer "B.Fab")
			(hide yes)
			(effects
				(font
					(size 1.016 1.016)
					(thickness 0.1524)
				)
				(justify mirror)
			)
		)
		(property "Device Type" "TPAD28"
			(at -0.0127 -3.3274 0)
			(unlocked yes)
			(layer "B.Fab")
			(hide yes)
			(effects
				(font
					(size 1.016 1.016)
					(thickness 0.1524)
				)
				(justify mirror)
			)
		)
		(duplicate_pad_numbers_are_jumpers no)
		(fp_poly
			(pts
				(arc
					(start 0.3556 0)
					(mid -0.3556 0)
					(end 0.3556 0)
				)
			)
			(stroke
				(width 0)
				(type default)
			)
			(fill no)
			(layer "B.CrtYd")
		)
		(fp_poly
			(pts
				(arc
					(start 0.6096 0)
					(mid -0.6096 0)
					(end 0.6096 0)
				)
			)
			(stroke
				(width 0)
				(type default)
			)
			(fill no)
			(layer "B.Fab")
		)
		(pad "1" smd circle
			(at 0 0 180)
			(size 0.7112 0.7112)
			(layers "B.Cu" "B.Mask" "B.Paste")
			(net "IOC_GPIO_19")
		)
	)
	(footprint ""
		(layer "B.Cu")
		(at 319.913 -165.354 90)
		(property "Reference" "R314"
			(at 0 0 90)
			(layer "B.SilkS")
			(hide yes)
			(effects
				(font
					(size 1.27 1.27)
				)
				(justify mirror)
			)
		)
		(property "Value" "4K7R2F-GP"
			(at -0.064008 -3.993896 90)
			(unlocked yes)
			(layer "B.Fab")
			(hide yes)
			(effects
				(font
					(size 1.016 1.016)
					(thickness 0.1524)
				)
				(justify mirror)
			)
		)
		(property "Device Type" "R402H16"
			(at -0.064008 -5.517896 90)
			(unlocked yes)
			(layer "B.Fab")
			(hide yes)
			(effects
				(font
					(size 1.016 1.016)
					(thickness 0.1524)
				)
				(justify mirror)
			)
		)
		(duplicate_pad_numbers_are_jumpers no)
		(fp_line
			(start 0.508 -0.9398)
			(end 0.508 0.9398)
			(stroke
				(width 0.1524)
				(type default)
			)
			(layer "B.SilkS")
		)
		(fp_line
			(start -0.508 -0.9398)
			(end 0.508 -0.9398)
			(stroke
				(width 0.1524)
				(type default)
			)
			(layer "B.SilkS")
		)
		(fp_rect
			(start 0.508 0.9398)
			(end -0.508 -0.9398)
			(stroke
				(width 0)
				(type default)
			)
			(fill no)
			(layer "B.CrtYd")
		)
		(fp_rect
			(start 0.508 0.9398)
			(end -0.508 -0.9398)
			(stroke
				(width 0)
				(type default)
			)
			(fill no)
			(layer "B.Fab")
		)
		(pad "1" smd custom
			(at 0 -0.4445 270)
			(size 0.1397 0.1397)
			(layers "B.Cu" "B.Mask" "B.Paste")
			(net "BMC_I2C_D_SDA")
			(options
				(clearance outline)
				(anchor circle)
			)
			(primitives
				(gr_poly
					(pts
						(arc
							(start -0.1778 0.2794)
							(mid -0.249642 0.249642)
							(end -0.2794 0.1778)
						)
						(arc
							(start -0.2794 -0.1778)
							(mid -0.249642 -0.249642)
							(end -0.1778 -0.2794)
						)
						(arc
							(start 0.1778 -0.2794)
							(mid 0.249642 -0.249642)
							(end 0.2794 -0.1778)
						)
						(arc
							(start 0.2794 0.1778)
							(mid 0.249642 0.249642)
							(end 0.1778 0.2794)
						)
					)
					(width 0)
					(fill yes)
				)
			)
		)
		(pad "2" smd custom
			(at 0 0.4445 270)
			(size 0.1397 0.1397)
			(layers "B.Cu" "B.Mask" "B.Paste")
			(net "P3V3_STBY")
			(options
				(clearance outline)
				(anchor circle)
			)
			(primitives
				(gr_poly
					(pts
						(arc
							(start -0.1778 0.2794)
							(mid -0.249642 0.249642)
							(end -0.2794 0.1778)
						)
						(arc
							(start -0.2794 -0.1778)
							(mid -0.249642 -0.249642)
							(end -0.1778 -0.2794)
						)
						(arc
							(start 0.1778 -0.2794)
							(mid 0.249642 -0.249642)
							(end 0.2794 -0.1778)
						)
						(arc
							(start 0.2794 0.1778)
							(mid 0.249642 0.249642)
							(end 0.1778 0.2794)
						)
					)
					(width 0)
					(fill yes)
				)
			)
		)
	)
	(footprint ""
		(layer "B.Cu")
		(at 117.61597 -81.915)
		(property "Reference" "STP112"
			(at 0 0 0)
			(layer "B.SilkS")
			(hide yes)
			(effects
				(font
					(size 1.27 1.27)
				)
				(justify mirror)
			)
		)
		(property "Value" "TPAD28"
			(at -0.0127 -1.8034 0)
			(unlocked yes)
			(layer "B.Fab")
			(hide yes)
			(effects
				(font
					(size 1.016 1.016)
					(thickness 0.1524)
				)
				(justify mirror)
			)
		)
		(property "Device Type" "TPAD28"
			(at -0.0127 -3.3274 0)
			(unlocked yes)
			(layer "B.Fab")
			(hide yes)
			(effects
				(font
					(size 1.016 1.016)
					(thickness 0.1524)
				)
				(justify mirror)
			)
		)
		(duplicate_pad_numbers_are_jumpers no)
		(fp_poly
			(pts
				(arc
					(start 0.3556 0)
					(mid -0.3556 0)
					(end 0.3556 0)
				)
			)
			(stroke
				(width 0)
				(type default)
			)
			(fill no)
			(layer "B.CrtYd")
		)
		(fp_poly
			(pts
				(arc
					(start 0.6096 0)
					(mid -0.6096 0)
					(end 0.6096 0)
				)
			)
			(stroke
				(width 0)
				(type default)
			)
			(fill no)
			(layer "B.Fab")
		)
		(pad "1" smd circle
			(at 0 0 180)
			(size 0.7112 0.7112)
			(layers "B.Cu" "B.Mask" "B.Paste")
			(net "TEST_MUX_45")
		)
	)
	(footprint ""
		(layer "B.Cu")
		(at 113.80597 -79.121)
		(property "Reference" "STP68"
			(at 0 0 0)
			(layer "B.SilkS")
			(hide yes)
			(effects
				(font
					(size 1.27 1.27)
				)
				(justify mirror)
			)
		)
		(property "Value" "TPAD28"
			(at -0.0127 -1.8034 0)
			(unlocked yes)
			(layer "B.Fab")
			(hide yes)
			(effects
				(font
					(size 1.016 1.016)
					(thickness 0.1524)
				)
				(justify mirror)
			)
		)
		(property "Device Type" "TPAD28"
			(at -0.0127 -3.3274 0)
			(unlocked yes)
			(layer "B.Fab")
			(hide yes)
			(effects
				(font
					(size 1.016 1.016)
					(thickness 0.1524)
				)
				(justify mirror)
			)
		)
		(duplicate_pad_numbers_are_jumpers no)
		(fp_poly
			(pts
				(arc
					(start 0.3556 0)
					(mid -0.3556 0)
					(end 0.3556 0)
				)
			)
			(stroke
				(width 0)
				(type default)
			)
			(fill no)
			(layer "B.CrtYd")
		)
		(fp_poly
			(pts
				(arc
					(start 0.6096 0)
					(mid -0.6096 0)
					(end 0.6096 0)
				)
			)
			(stroke
				(width 0)
				(type default)
			)
			(fill no)
			(layer "B.Fab")
		)
		(pad "1" smd circle
			(at 0 0 180)
			(size 0.7112 0.7112)
			(layers "B.Cu" "B.Mask" "B.Paste")
			(net "EXP_TEST_MUX30")
		)
	)
	(footprint ""
		(layer "B.Cu")
		(at 107.42676 -33.782)
		(property "Reference" "STP77"
			(at 0 0 0)
			(layer "B.SilkS")
			(hide yes)
			(effects
				(font
					(size 1.27 1.27)
				)
				(justify mirror)
			)
		)
		(property "Value" "TPAD28"
			(at -0.0127 -1.8034 0)
			(unlocked yes)
			(layer "B.Fab")
			(hide yes)
			(effects
				(font
					(size 1.016 1.016)
					(thickness 0.1524)
				)
				(justify mirror)
			)
		)
		(property "Device Type" "TPAD28"
			(at -0.0127 -3.3274 0)
			(unlocked yes)
			(layer "B.Fab")
			(hide yes)
			(effects
				(font
					(size 1.016 1.016)
					(thickness 0.1524)
				)
				(justify mirror)
			)
		)
		(duplicate_pad_numbers_are_jumpers no)
		(fp_poly
			(pts
				(arc
					(start 0.3556 0)
					(mid -0.3556 0)
					(end 0.3556 0)
				)
			)
			(stroke
				(width 0)
				(type default)
			)
			(fill no)
			(layer "B.CrtYd")
		)
		(fp_poly
			(pts
				(arc
					(start 0.6096 0)
					(mid -0.6096 0)
					(end 0.6096 0)
				)
			)
			(stroke
				(width 0)
				(type default)
			)
			(fill no)
			(layer "B.Fab")
		)
		(pad "1" smd circle
			(at 0 0 180)
			(size 0.7112 0.7112)
			(layers "B.Cu" "B.Mask" "B.Paste")
			(net "IOC_GPIO_2")
		)
	)
	(footprint ""
		(layer "B.Cu")
		(at 114.56797 -98.425 180)
		(property "Reference" "SC1220"
			(at 0 0 0)
			(layer "B.SilkS")
			(hide yes)
			(effects
				(font
					(size 1.27 1.27)
				)
				(justify mirror)
			)
		)
		(property "Value" "SC1KP50V2KX-1GP"
			(at -1.1811 -2.7051 180)
			(unlocked yes)
			(layer "B.Fab")
			(hide yes)
			(effects
				(font
					(size 1.016 1.016)
					(thickness 0.1524)
				)
				(justify mirror)
			)
		)
		(property "Device Type" "C402H22"
			(at -1.1811 -4.2291 180)
			(unlocked yes)
			(layer "B.Fab")
			(hide yes)
			(effects
				(font
					(size 1.016 1.016)
					(thickness 0.1524)
				)
				(justify mirror)
			)
		)
		(duplicate_pad_numbers_are_jumpers no)
		(fp_rect
			(start 0.4318 0.9525)
			(end -0.4318 -0.9525)
			(stroke
				(width 0)
				(type default)
			)
			(fill no)
			(layer "B.CrtYd")
		)
		(fp_rect
			(start 0.4318 0.9525)
			(end -0.4318 -0.9525)
			(stroke
				(width 0)
				(type default)
			)
			(fill no)
			(layer "B.Fab")
		)
		(pad "1" smd custom
			(at 0 -0.4445)
			(size 0.1524 0.1524)
			(layers "B.Cu" "B.Mask" "B.Paste")
			(net "P0V9_E")
			(options
				(clearance outline)
				(anchor circle)
			)
			(primitives
				(gr_poly
					(pts
						(arc
							(start 0.3048 0.2032)
							(mid 0.275042 0.275042)
							(end 0.2032 0.3048)
						)
						(arc
							(start -0.2032 0.3048)
							(mid -0.275042 0.275042)
							(end -0.3048 0.2032)
						)
						(arc
							(start -0.3048 -0.2032)
							(mid -0.275042 -0.275042)
							(end -0.2032 -0.3048)
						)
						(arc
							(start 0.2032 -0.3048)
							(mid 0.275042 -0.275042)
							(end 0.3048 -0.2032)
						)
					)
					(width 0)
					(fill yes)
				)
			)
		)
		(pad "2" smd custom
			(at 0 0.4445)
			(size 0.1524 0.1524)
			(layers "B.Cu" "B.Mask" "B.Paste")
			(net "GND")
			(options
				(clearance outline)
				(anchor circle)
			)
			(primitives
				(gr_poly
					(pts
						(arc
							(start 0.3048 0.2032)
							(mid 0.275042 0.275042)
							(end 0.2032 0.3048)
						)
						(arc
							(start -0.2032 0.3048)
							(mid -0.275042 0.275042)
							(end -0.3048 0.2032)
						)
						(arc
							(start -0.3048 -0.2032)
							(mid -0.275042 -0.275042)
							(end -0.2032 -0.3048)
						)
						(arc
							(start 0.2032 -0.3048)
							(mid 0.275042 -0.275042)
							(end 0.3048 -0.2032)
						)
					)
					(width 0)
					(fill yes)
				)
			)
		)
	)
	(footprint ""
		(layer "B.Cu")
		(at 310.007 -50.927 180)
		(property "Reference" "C279"
			(at 0 0 0)
			(layer "B.SilkS")
			(hide yes)
			(effects
				(font
					(size 1.27 1.27)
				)
				(justify mirror)
			)
		)
		(property "Value" "SCD1U25V2KX-2-GP"
			(at -1.1811 -2.7051 180)
			(unlocked yes)
			(layer "B.Fab")
			(hide yes)
			(effects
				(font
					(size 1.016 1.016)
					(thickness 0.1524)
				)
				(justify mirror)
			)
		)
		(property "Device Type" "C402H22"
			(at -1.1811 -4.2291 180)
			(unlocked yes)
			(layer "B.Fab")
			(hide yes)
			(effects
				(font
					(size 1.016 1.016)
					(thickness 0.1524)
				)
				(justify mirror)
			)
		)
		(duplicate_pad_numbers_are_jumpers no)
		(fp_rect
			(start 0.4318 0.9525)
			(end -0.4318 -0.9525)
			(stroke
				(width 0)
				(type default)
			)
			(fill no)
			(layer "B.CrtYd")
		)
		(fp_rect
			(start 0.4318 0.9525)
			(end -0.4318 -0.9525)
			(stroke
				(width 0)
				(type default)
			)
			(fill no)
			(layer "B.Fab")
		)
		(pad "1" smd custom
			(at 0 -0.4445)
			(size 0.1524 0.1524)
			(layers "B.Cu" "B.Mask" "B.Paste")
			(net "P12V")
			(options
				(clearance outline)
				(anchor circle)
			)
			(primitives
				(gr_poly
					(pts
						(arc
							(start 0.3048 0.2032)
							(mid 0.275042 0.275042)
							(end 0.2032 0.3048)
						)
						(arc
							(start -0.2032 0.3048)
							(mid -0.275042 0.275042)
							(end -0.3048 0.2032)
						)
						(arc
							(start -0.3048 -0.2032)
							(mid -0.275042 -0.275042)
							(end -0.2032 -0.3048)
						)
						(arc
							(start 0.2032 -0.3048)
							(mid 0.275042 -0.275042)
							(end 0.3048 -0.2032)
						)
					)
					(width 0)
					(fill yes)
				)
			)
		)
		(pad "2" smd custom
			(at 0 0.4445)
			(size 0.1524 0.1524)
			(layers "B.Cu" "B.Mask" "B.Paste")
			(net "GND")
			(options
				(clearance outline)
				(anchor circle)
			)
			(primitives
				(gr_poly
					(pts
						(arc
							(start 0.3048 0.2032)
							(mid 0.275042 0.275042)
							(end 0.2032 0.3048)
						)
						(arc
							(start -0.2032 0.3048)
							(mid -0.275042 0.275042)
							(end -0.3048 0.2032)
						)
						(arc
							(start -0.3048 -0.2032)
							(mid -0.275042 -0.275042)
							(end -0.2032 -0.3048)
						)
						(arc
							(start 0.2032 -0.3048)
							(mid 0.275042 -0.275042)
							(end 0.3048 -0.2032)
						)
					)
					(width 0)
					(fill yes)
				)
			)
		)
	)
	(footprint ""
		(layer "B.Cu")
		(at 286.41294 -168.56964)
		(property "Reference" "TP118"
			(at 0 0 0)
			(layer "B.SilkS")
			(hide yes)
			(effects
				(font
					(size 1.27 1.27)
				)
				(justify mirror)
			)
		)
		(property "Value" "TPAD28"
			(at -0.0127 -1.8034 0)
			(unlocked yes)
			(layer "B.Fab")
			(hide yes)
			(effects
				(font
					(size 1.016 1.016)
					(thickness 0.1524)
				)
				(justify mirror)
			)
		)
		(property "Device Type" "TPAD28"
			(at -0.0127 -3.3274 0)
			(unlocked yes)
			(layer "B.Fab")
			(hide yes)
			(effects
				(font
					(size 1.016 1.016)
					(thickness 0.1524)
				)
				(justify mirror)
			)
		)
		(duplicate_pad_numbers_are_jumpers no)
		(fp_poly
			(pts
				(arc
					(start 0.3556 0)
					(mid -0.3556 0)
					(end 0.3556 0)
				)
			)
			(stroke
				(width 0)
				(type default)
			)
			(fill no)
			(layer "B.CrtYd")
		)
		(fp_poly
			(pts
				(arc
					(start 0.6096 0)
					(mid -0.6096 0)
					(end 0.6096 0)
				)
			)
			(stroke
				(width 0)
				(type default)
			)
			(fill no)
			(layer "B.Fab")
		)
		(pad "1" smd circle
			(at 0 0 180)
			(size 0.7112 0.7112)
			(layers "B.Cu" "B.Mask" "B.Paste")
			(net "TP_BMC_GPIOF0")
		)
	)
)
